(kicad_pcb
	(version 20260206)
	(generator "pcbnew")
	(generator_version "10.0")
	(general
		(thickness 1.6)
		(legacy_teardrops no)
	)
	(paper "A4")
	(title_block
		(title "peb — Lightning_PEB_BRD.brd")
		(comment 1 "Lightning (Wiwynn / Facebook NVMe JBOF) / footprints 335-341 of 2563")
	)
	(layers
		(0 "F.Cu" signal "TOP")
		(4 "In1.Cu" signal "L2GND")
		(6 "In2.Cu" signal "L3")
		(8 "In3.Cu" signal "L4VCC")
		(10 "In4.Cu" signal "L5VCC")
		(12 "In5.Cu" signal "L6")
		(14 "In6.Cu" signal "L7GND")
		(2 "B.Cu" signal "BOTTOM")
		(9 "F.Adhes" user "F.Adhesive")
		(11 "B.Adhes" user "B.Adhesive")
		(13 "F.Paste" user "Package Geometry/Pastemask Top")
		(15 "B.Paste" user "Package Geometry/Pastemask Bottom")
		(5 "F.SilkS" user "Ref Des/Silkscreen Top")
		(7 "B.SilkS" user "Ref Des/Silkscreen Bottom")
		(1 "F.Mask" user "Board Geometry/Soldermask Top")
		(3 "B.Mask" user "Board Geometry/Soldermask Bottom")
		(17 "Dwgs.User" user "User.Drawings")
		(19 "Cmts.User" user "User.Comments")
		(21 "Eco1.User" user "User.Eco1")
		(23 "Eco2.User" user "User.Eco2")
		(25 "Edge.Cuts" user "Board Geometry/Outline")
		(27 "Margin" user)
		(31 "F.CrtYd" user "Package Geometry/Place Bound Top")
		(29 "B.CrtYd" user "Package Geometry/Place Bound Bottom")
		(35 "F.Fab" user "Ref Des/Assembly Top")
		(33 "B.Fab" user "Ref Des/Assembly Bottom")
	)
	(footprint ""
		(layer "F.Cu")
		(at 330.740512 -172.432218 180)
		(property "Reference" "R575"
			(at 0 0 180)
			(layer "F.SilkS")
			(hide yes)
			(effects
				(font
					(size 1.27 1.27)
				)
			)
		)
		(property "Value" "10KR2F-2-GP"
			(at 0.064008 -3.993896 180)
			(unlocked yes)
			(layer "F.Fab")
			(hide yes)
			(effects
				(font
					(size 1.016 1.016)
					(thickness 0.1524)
				)
			)
		)
		(property "Device Type" "R402H16"
			(at 0.064008 -5.517896 180)
			(unlocked yes)
			(layer "F.Fab")
			(hide yes)
			(effects
				(font
					(size 1.016 1.016)
					(thickness 0.1524)
				)
			)
		)
		(duplicate_pad_numbers_are_jumpers no)
		(fp_line
			(start 0.508 -0.9398)
			(end -0.508 -0.9398)
			(stroke
				(width 0.1524)
				(type default)
			)
			(layer "F.SilkS")
		)
		(fp_line
			(start -0.508 -0.9398)
			(end -0.508 0.9398)
			(stroke
				(width 0.1524)
				(type default)
			)
			(layer "F.SilkS")
		)
		(fp_rect
			(start -0.508 0.9398)
			(end 0.508 -0.9398)
			(stroke
				(width 0)
				(type default)
			)
			(fill no)
			(layer "F.CrtYd")
		)
		(fp_rect
			(start -0.508 0.9398)
			(end 0.508 -0.9398)
			(stroke
				(width 0)
				(type default)
			)
			(fill no)
			(layer "F.Fab")
		)
		(pad "1" smd custom
			(at 0 -0.4445 180)
			(size 0.1397 0.1397)
			(layers "F.Cu" "F.Mask" "F.Paste")
			(net "GND")
			(options
				(clearance outline)
				(anchor circle)
			)
			(primitives
				(gr_poly
					(pts
						(arc
							(start -0.1778 -0.2794)
							(mid -0.249642 -0.249642)
							(end -0.2794 -0.1778)
						)
						(arc
							(start -0.2794 0.1778)
							(mid -0.249642 0.249642)
							(end -0.1778 0.2794)
						)
						(arc
							(start 0.1778 0.2794)
							(mid 0.249642 0.249642)
							(end 0.2794 0.1778)
						)
						(arc
							(start 0.2794 -0.1778)
							(mid 0.249642 -0.249642)
							(end 0.1778 -0.2794)
						)
					)
					(width 0)
					(fill yes)
				)
			)
		)
		(pad "2" smd custom
			(at 0 0.4445 180)
			(size 0.1397 0.1397)
			(layers "F.Cu" "F.Mask" "F.Paste")
			(net "IOEXP4_AD1")
			(options
				(clearance outline)
				(anchor circle)
			)
			(primitives
				(gr_poly
					(pts
						(arc
							(start -0.1778 -0.2794)
							(mid -0.249642 -0.249642)
							(end -0.2794 -0.1778)
						)
						(arc
							(start -0.2794 0.1778)
							(mid -0.249642 0.249642)
							(end -0.1778 0.2794)
						)
						(arc
							(start 0.1778 0.2794)
							(mid 0.249642 0.249642)
							(end 0.2794 0.1778)
						)
						(arc
							(start 0.2794 -0.1778)
							(mid 0.249642 -0.249642)
							(end 0.1778 -0.2794)
						)
					)
					(width 0)
					(fill yes)
				)
			)
		)
	)
	(footprint ""
		(layer "F.Cu")
		(at 345.188794 -45.893736)
		(property "Reference" "R7902"
			(at 0 0 0)
			(layer "F.SilkS")
			(hide yes)
			(effects
				(font
					(size 1.27 1.27)
				)
			)
		)
		(property "Value" "0R2J-2-GP"
			(at 0.064008 -3.993896 0)
			(unlocked yes)
			(layer "F.Fab")
			(hide yes)
			(effects
				(font
					(size 1.016 1.016)
					(thickness 0.1524)
				)
			)
		)
		(property "Device Type" "R402H16"
			(at 0.064008 -5.517896 0)
			(unlocked yes)
			(layer "F.Fab")
			(hide yes)
			(effects
				(font
					(size 1.016 1.016)
					(thickness 0.1524)
				)
			)
		)
		(duplicate_pad_numbers_are_jumpers no)
		(fp_line
			(start -0.508 -0.9398)
			(end -0.508 0.9398)
			(stroke
				(width 0.1524)
				(type default)
			)
			(layer "F.SilkS")
		)
		(fp_line
			(start 0.508 -0.9398)
			(end -0.508 -0.9398)
			(stroke
				(width 0.1524)
				(type default)
			)
			(layer "F.SilkS")
		)
		(fp_rect
			(start -0.508 0.9398)
			(end 0.508 -0.9398)
			(stroke
				(width 0)
				(type default)
			)
			(fill no)
			(layer "F.CrtYd")
		)
		(fp_rect
			(start -0.508 0.9398)
			(end 0.508 -0.9398)
			(stroke
				(width 0)
				(type default)
			)
			(fill no)
			(layer "F.Fab")
		)
		(pad "1" smd custom
			(at 0 -0.4445)
			(size 0.1397 0.1397)
			(layers "F.Cu" "F.Mask" "F.Paste")
			(net "PM8536_RST#_AND")
			(options
				(clearance outline)
				(anchor circle)
			)
			(primitives
				(gr_poly
					(pts
						(arc
							(start -0.1778 -0.2794)
							(mid -0.249642 -0.249642)
							(end -0.2794 -0.1778)
						)
						(arc
							(start -0.2794 0.1778)
							(mid -0.249642 0.249642)
							(end -0.1778 0.2794)
						)
						(arc
							(start 0.1778 0.2794)
							(mid 0.249642 0.249642)
							(end 0.2794 0.1778)
						)
						(arc
							(start 0.2794 -0.1778)
							(mid 0.249642 -0.249642)
							(end 0.1778 -0.2794)
						)
					)
					(width 0)
					(fill yes)
				)
			)
		)
		(pad "2" smd custom
			(at 0 0.4445)
			(size 0.1397 0.1397)
			(layers "F.Cu" "F.Mask" "F.Paste")
			(net "PM8536_RST#_LS")
			(options
				(clearance outline)
				(anchor circle)
			)
			(primitives
				(gr_poly
					(pts
						(arc
							(start -0.1778 -0.2794)
							(mid -0.249642 -0.249642)
							(end -0.2794 -0.1778)
						)
						(arc
							(start -0.2794 0.1778)
							(mid -0.249642 0.249642)
							(end -0.1778 0.2794)
						)
						(arc
							(start 0.1778 0.2794)
							(mid 0.249642 0.249642)
							(end 0.2794 0.1778)
						)
						(arc
							(start 0.2794 -0.1778)
							(mid 0.249642 -0.249642)
							(end 0.1778 -0.2794)
						)
					)
					(width 0)
					(fill yes)
				)
			)
		)
	)
	(footprint ""
		(layer "F.Cu")
		(at 68.8594 -118.6942 -90)
		(property "Reference" "R307"
			(at 0 0 270)
			(layer "F.SilkS")
			(hide yes)
			(effects
				(font
					(size 1.27 1.27)
				)
			)
		)
		(property "Value" "4K7R2F-GP"
			(at 0.064008 -3.993896 270)
			(unlocked yes)
			(layer "F.Fab")
			(hide yes)
			(effects
				(font
					(size 1.016 1.016)
					(thickness 0.1524)
				)
			)
		)
		(property "Device Type" "R402H16"
			(at 0.064008 -5.517896 270)
			(unlocked yes)
			(layer "F.Fab")
			(hide yes)
			(effects
				(font
					(size 1.016 1.016)
					(thickness 0.1524)
				)
			)
		)
		(duplicate_pad_numbers_are_jumpers no)
		(fp_line
			(start -0.508 -0.9398)
			(end -0.508 0.9398)
			(stroke
				(width 0.1524)
				(type default)
			)
			(layer "F.SilkS")
		)
		(fp_line
			(start 0.508 -0.9398)
			(end -0.508 -0.9398)
			(stroke
				(width 0.1524)
				(type default)
			)
			(layer "F.SilkS")
		)
		(fp_rect
			(start -0.508 0.9398)
			(end 0.508 -0.9398)
			(stroke
				(width 0)
				(type default)
			)
			(fill no)
			(layer "F.CrtYd")
		)
		(fp_rect
			(start -0.508 0.9398)
			(end 0.508 -0.9398)
			(stroke
				(width 0)
				(type default)
			)
			(fill no)
			(layer "F.Fab")
		)
		(pad "1" smd custom
			(at 0 -0.4445 270)
			(size 0.1397 0.1397)
			(layers "F.Cu" "F.Mask" "F.Paste")
			(net "P3V3_STBY")
			(options
				(clearance outline)
				(anchor circle)
			)
			(primitives
				(gr_poly
					(pts
						(arc
							(start -0.1778 -0.2794)
							(mid -0.249642 -0.249642)
							(end -0.2794 -0.1778)
						)
						(arc
							(start -0.2794 0.1778)
							(mid -0.249642 0.249642)
							(end -0.1778 0.2794)
						)
						(arc
							(start 0.1778 0.2794)
							(mid 0.249642 0.249642)
							(end 0.2794 0.1778)
						)
						(arc
							(start 0.2794 -0.1778)
							(mid 0.249642 -0.249642)
							(end 0.1778 -0.2794)
						)
					)
					(width 0)
					(fill yes)
				)
			)
		)
		(pad "2" smd custom
			(at 0 0.4445 270)
			(size 0.1397 0.1397)
			(layers "F.Cu" "F.Mask" "F.Paste")
			(net "I2C4_LS_G2")
			(options
				(clearance outline)
				(anchor circle)
			)
			(primitives
				(gr_poly
					(pts
						(arc
							(start -0.1778 -0.2794)
							(mid -0.249642 -0.249642)
							(end -0.2794 -0.1778)
						)
						(arc
							(start -0.2794 0.1778)
							(mid -0.249642 0.249642)
							(end -0.1778 0.2794)
						)
						(arc
							(start 0.1778 0.2794)
							(mid 0.249642 0.249642)
							(end 0.2794 0.1778)
						)
						(arc
							(start 0.2794 -0.1778)
							(mid 0.249642 -0.249642)
							(end 0.1778 -0.2794)
						)
					)
					(width 0)
					(fill yes)
				)
			)
		)
	)
	(footprint ""
		(layer "F.Cu")
		(at 181.864 -16.256 -90)
		(property "Reference" "SR718"
			(at 0 0 270)
			(layer "F.SilkS")
			(hide yes)
			(effects
				(font
					(size 1.27 1.27)
				)
			)
		)
		(property "Value" "150R2F-1-GP"
			(at 0.064008 -3.993896 270)
			(unlocked yes)
			(layer "F.Fab")
			(hide yes)
			(effects
				(font
					(size 1.016 1.016)
					(thickness 0.1524)
				)
			)
		)
		(property "Device Type" "R402H16"
			(at 0.064008 -5.517896 270)
			(unlocked yes)
			(layer "F.Fab")
			(hide yes)
			(effects
				(font
					(size 1.016 1.016)
					(thickness 0.1524)
				)
			)
		)
		(duplicate_pad_numbers_are_jumpers no)
		(fp_line
			(start -0.508 -0.9398)
			(end -0.508 0.9398)
			(stroke
				(width 0.1524)
				(type default)
			)
			(layer "F.SilkS")
		)
		(fp_line
			(start 0.508 -0.9398)
			(end -0.508 -0.9398)
			(stroke
				(width 0.1524)
				(type default)
			)
			(layer "F.SilkS")
		)
		(fp_rect
			(start -0.508 0.9398)
			(end 0.508 -0.9398)
			(stroke
				(width 0)
				(type default)
			)
			(fill no)
			(layer "F.CrtYd")
		)
		(fp_rect
			(start -0.508 0.9398)
			(end 0.508 -0.9398)
			(stroke
				(width 0)
				(type default)
			)
			(fill no)
			(layer "F.Fab")
		)
		(pad "1" smd custom
			(at 0 -0.4445 270)
			(size 0.1397 0.1397)
			(layers "F.Cu" "F.Mask" "F.Paste")
			(net "P3V3_STBY")
			(options
				(clearance outline)
				(anchor circle)
			)
			(primitives
				(gr_poly
					(pts
						(arc
							(start -0.1778 -0.2794)
							(mid -0.249642 -0.249642)
							(end -0.2794 -0.1778)
						)
						(arc
							(start -0.2794 0.1778)
							(mid -0.249642 0.249642)
							(end -0.1778 0.2794)
						)
						(arc
							(start 0.1778 0.2794)
							(mid 0.249642 0.249642)
							(end 0.2794 0.1778)
						)
						(arc
							(start 0.2794 -0.1778)
							(mid 0.249642 -0.249642)
							(end 0.1778 -0.2794)
						)
					)
					(width 0)
					(fill yes)
				)
			)
		)
		(pad "2" smd custom
			(at 0 0.4445 270)
			(size 0.1397 0.1397)
			(layers "F.Cu" "F.Mask" "F.Paste")
			(net "LED_R_9")
			(options
				(clearance outline)
				(anchor circle)
			)
			(primitives
				(gr_poly
					(pts
						(arc
							(start -0.1778 -0.2794)
							(mid -0.249642 -0.249642)
							(end -0.2794 -0.1778)
						)
						(arc
							(start -0.2794 0.1778)
							(mid -0.249642 0.249642)
							(end -0.1778 0.2794)
						)
						(arc
							(start 0.1778 0.2794)
							(mid 0.249642 0.249642)
							(end 0.2794 0.1778)
						)
						(arc
							(start 0.2794 -0.1778)
							(mid 0.249642 -0.249642)
							(end 0.1778 -0.2794)
						)
					)
					(width 0)
					(fill yes)
				)
			)
		)
	)
	(footprint ""
		(layer "F.Cu")
		(at 47.244 -180.467)
		(property "Reference" "C265"
			(at 0 0 0)
			(layer "F.SilkS")
			(hide yes)
			(effects
				(font
					(size 1.27 1.27)
				)
			)
		)
		(property "Value" "SCD01U50V2KX-1GP"
			(at 1.1811 -2.7051 0)
			(unlocked yes)
			(layer "F.Fab")
			(hide yes)
			(effects
				(font
					(size 1.016 1.016)
					(thickness 0.1524)
				)
			)
		)
		(property "Device Type" "C402H22"
			(at 1.1811 -4.2291 0)
			(unlocked yes)
			(layer "F.Fab")
			(hide yes)
			(effects
				(font
					(size 1.016 1.016)
					(thickness 0.1524)
				)
			)
		)
		(duplicate_pad_numbers_are_jumpers no)
		(fp_rect
			(start -0.4318 0.9525)
			(end 0.4318 -0.9525)
			(stroke
				(width 0)
				(type default)
			)
			(fill no)
			(layer "F.CrtYd")
		)
		(fp_rect
			(start -0.4318 0.9525)
			(end 0.4318 -0.9525)
			(stroke
				(width 0)
				(type default)
			)
			(fill no)
			(layer "F.Fab")
		)
		(pad "1" smd custom
			(at 0 -0.4445)
			(size 0.1524 0.1524)
			(layers "F.Cu" "F.Mask" "F.Paste")
			(net "P3V3_STBY")
			(options
				(clearance outline)
				(anchor circle)
			)
			(primitives
				(gr_poly
					(pts
						(arc
							(start 0.3048 -0.2032)
							(mid 0.275042 -0.275042)
							(end 0.2032 -0.3048)
						)
						(arc
							(start -0.2032 -0.3048)
							(mid -0.275042 -0.275042)
							(end -0.3048 -0.2032)
						)
						(arc
							(start -0.3048 0.2032)
							(mid -0.275042 0.275042)
							(end -0.2032 0.3048)
						)
						(arc
							(start 0.2032 0.3048)
							(mid 0.275042 0.275042)
							(end 0.3048 0.2032)
						)
					)
					(width 0)
					(fill yes)
				)
			)
		)
		(pad "2" smd custom
			(at 0 0.4445)
			(size 0.1524 0.1524)
			(layers "F.Cu" "F.Mask" "F.Paste")
			(net "GND")
			(options
				(clearance outline)
				(anchor circle)
			)
			(primitives
				(gr_poly
					(pts
						(arc
							(start 0.3048 -0.2032)
							(mid 0.275042 -0.275042)
							(end 0.2032 -0.3048)
						)
						(arc
							(start -0.2032 -0.3048)
							(mid -0.275042 -0.275042)
							(end -0.3048 -0.2032)
						)
						(arc
							(start -0.3048 0.2032)
							(mid -0.275042 0.275042)
							(end -0.2032 0.3048)
						)
						(arc
							(start 0.2032 0.3048)
							(mid 0.275042 0.275042)
							(end 0.3048 0.2032)
						)
					)
					(width 0)
					(fill yes)
				)
			)
		)
	)
	(footprint ""
		(layer "F.Cu")
		(at 67.749166 -90.33256 180)
		(property "Reference" "R483"
			(at 0 0 180)
			(layer "F.SilkS")
			(hide yes)
			(effects
				(font
					(size 1.27 1.27)
				)
			)
		)
		(property "Value" "0R2J-2-GP"
			(at 0.064008 -3.993896 180)
			(unlocked yes)
			(layer "F.Fab")
			(hide yes)
			(effects
				(font
					(size 1.016 1.016)
					(thickness 0.1524)
				)
			)
		)
		(property "Device Type" "R402H16"
			(at 0.064008 -5.517896 180)
			(unlocked yes)
			(layer "F.Fab")
			(hide yes)
			(effects
				(font
					(size 1.016 1.016)
					(thickness 0.1524)
				)
			)
		)
		(duplicate_pad_numbers_are_jumpers no)
		(fp_line
			(start 0.508 -0.9398)
			(end -0.508 -0.9398)
			(stroke
				(width 0.1524)
				(type default)
			)
			(layer "F.SilkS")
		)
		(fp_line
			(start -0.508 -0.9398)
			(end -0.508 0.9398)
			(stroke
				(width 0.1524)
				(type default)
			)
			(layer "F.SilkS")
		)
		(fp_rect
			(start -0.508 0.9398)
			(end 0.508 -0.9398)
			(stroke
				(width 0)
				(type default)
			)
			(fill no)
			(layer "F.CrtYd")
		)
		(fp_rect
			(start -0.508 0.9398)
			(end 0.508 -0.9398)
			(stroke
				(width 0)
				(type default)
			)
			(fill no)
			(layer "F.Fab")
		)
		(pad "1" smd custom
			(at 0 -0.4445 180)
			(size 0.1397 0.1397)
			(layers "F.Cu" "F.Mask" "F.Paste")
			(net "HB_A_OUT")
			(options
				(clearance outline)
				(anchor circle)
			)
			(primitives
				(gr_poly
					(pts
						(arc
							(start -0.1778 -0.2794)
							(mid -0.249642 -0.249642)
							(end -0.2794 -0.1778)
						)
						(arc
							(start -0.2794 0.1778)
							(mid -0.249642 0.249642)
							(end -0.1778 0.2794)
						)
						(arc
							(start 0.1778 0.2794)
							(mid 0.249642 0.249642)
							(end 0.2794 0.1778)
						)
						(arc
							(start 0.2794 -0.1778)
							(mid 0.249642 -0.249642)
							(end 0.1778 -0.2794)
						)
					)
					(width 0)
					(fill yes)
				)
			)
		)
		(pad "2" smd custom
			(at 0 0.4445 180)
			(size 0.1397 0.1397)
			(layers "F.Cu" "F.Mask" "F.Paste")
			(net "HB_OUT")
			(options
				(clearance outline)
				(anchor circle)
			)
			(primitives
				(gr_poly
					(pts
						(arc
							(start -0.1778 -0.2794)
							(mid -0.249642 -0.249642)
							(end -0.2794 -0.1778)
						)
						(arc
							(start -0.2794 0.1778)
							(mid -0.249642 0.249642)
							(end -0.1778 0.2794)
						)
						(arc
							(start 0.1778 0.2794)
							(mid 0.249642 0.249642)
							(end 0.2794 0.1778)
						)
						(arc
							(start 0.2794 -0.1778)
							(mid 0.249642 -0.249642)
							(end 0.1778 -0.2794)
						)
					)
					(width 0)
					(fill yes)
				)
			)
		)
	)
	(footprint ""
		(layer "F.Cu")
		(at 275.008086 -212.420454 180)
		(property "Reference" "C100"
			(at 0 0 180)
			(layer "F.SilkS")
			(hide yes)
			(effects
				(font
					(size 1.27 1.27)
				)
			)
		)
		(property "Value" "SCD22U10V2KX-1GP"
			(at 1.1811 -2.7051 180)
			(unlocked yes)
			(layer "F.Fab")
			(hide yes)
			(effects
				(font
					(size 1.016 1.016)
					(thickness 0.1524)
				)
			)
		)
		(property "Device Type" "C402H22"
			(at 1.1811 -4.2291 180)
			(unlocked yes)
			(layer "F.Fab")
			(hide yes)
			(effects
				(font
					(size 1.016 1.016)
					(thickness 0.1524)
				)
			)
		)
		(duplicate_pad_numbers_are_jumpers no)
		(fp_rect
			(start -0.4318 0.9525)
			(end 0.4318 -0.9525)
			(stroke
				(width 0)
				(type default)
			)
			(fill no)
			(layer "F.CrtYd")
		)
		(fp_rect
			(start -0.4318 0.9525)
			(end 0.4318 -0.9525)
			(stroke
				(width 0)
				(type default)
			)
			(fill no)
			(layer "F.Fab")
		)
		(pad "1" smd custom
			(at 0 -0.4445 180)
			(size 0.1524 0.1524)
			(layers "F.Cu" "F.Mask" "F.Paste")
			(net "PCIE_TX_CAP_N34")
			(options
				(clearance outline)
				(anchor circle)
			)
			(primitives
				(gr_poly
					(pts
						(arc
							(start 0.3048 -0.2032)
							(mid 0.275042 -0.275042)
							(end 0.2032 -0.3048)
						)
						(arc
							(start -0.2032 -0.3048)
							(mid -0.275042 -0.275042)
							(end -0.3048 -0.2032)
						)
						(arc
							(start -0.3048 0.2032)
							(mid -0.275042 0.275042)
							(end -0.2032 0.3048)
						)
						(arc
							(start 0.2032 0.3048)
							(mid 0.275042 0.275042)
							(end 0.3048 0.2032)
						)
					)
					(width 0)
					(fill yes)
				)
			)
		)
		(pad "2" smd custom
			(at 0 0.4445 180)
			(size 0.1524 0.1524)
			(layers "F.Cu" "F.Mask" "F.Paste")
			(net "PCIE_TX_N34")
			(options
				(clearance outline)
				(anchor circle)
			)
			(primitives
				(gr_poly
					(pts
						(arc
							(start 0.3048 -0.2032)
							(mid 0.275042 -0.275042)
							(end 0.2032 -0.3048)
						)
						(arc
							(start -0.2032 -0.3048)
							(mid -0.275042 -0.275042)
							(end -0.3048 -0.2032)
						)
						(arc
							(start -0.3048 0.2032)
							(mid -0.275042 0.275042)
							(end -0.2032 0.3048)
						)
						(arc
							(start 0.2032 0.3048)
							(mid 0.275042 0.275042)
							(end 0.3048 0.2032)
						)
					)
					(width 0)
					(fill yes)
				)
			)
		)
	)
)
